# BASEBOARD_FAB2 (Tioga Pass) — schematic netlist excerpt (pin names and nets, part order shuffled) for the footprints in the layout excerpt that follows; sources: Cadence DE-HDL packaged netlist, KiCad conversion of Wiwynn_Tioga_Pass_MB.brd

R2N6  RES  10.0K 1% CHIP  pkg 0402  page 118 : A = P3V3_STBY ; B = FM_GBE_LOM_DISABLE_N
C8E13  CAP  1000PF 50V 10% EMPTY  pkg 0402LF  page 241 : A = PWRGD_P12V_HSC_DLY ; B = AGND_P5V_STBY
R4B7  RES  22.1 1.0% CHIP  pkg 0402  page 234 : A = PWRGD_PVPP_KLM_R ; B = PWRGD_PVPP_KLM

(kicad_pcb
	(version 20260206)
	(generator "pcbnew")
	(generator_version "10.0")
	(general
		(thickness 1.6)
		(legacy_teardrops no)
	)
	(paper "A4")
	(title_block
		(title "Wiwynn_Tioga_Pass_MB.brd")
		(comment 1 "Tioga Pass / footprints 1419-1421 of 4770")
	)
	(layers
		(0 "F.Cu" signal "TOP")
		(4 "In1.Cu" signal "L2GND")
		(6 "In2.Cu" signal "L3")
		(8 "In3.Cu" signal "L4GND")
		(10 "In4.Cu" signal "L5")
		(12 "In5.Cu" signal "L6GND")
		(14 "In6.Cu" signal "L7VCC")
		(16 "In7.Cu" signal "L8VCC")
		(18 "In8.Cu" signal "L9GND")
		(20 "In9.Cu" signal "L10")
		(22 "In10.Cu" signal "L11GND")
		(24 "In11.Cu" signal "L12")
		(26 "In12.Cu" signal "L13GND")
		(2 "B.Cu" signal "BOTTOM")
		(9 "F.Adhes" user "F.Adhesive")
		(11 "B.Adhes" user "B.Adhesive")
		(13 "F.Paste" user "Package Geometry/Pastemask Top")
		(15 "B.Paste" user "Package Geometry/Pastemask Bottom")
		(5 "F.SilkS" user "Ref Des/Silkscreen Top")
		(7 "B.SilkS" user "Ref Des/Silkscreen Bottom")
		(1 "F.Mask" user "Board Geometry/Soldermask Top")
		(3 "B.Mask" user "Board Geometry/Soldermask Bottom")
		(17 "Dwgs.User" user "User.Drawings")
		(19 "Cmts.User" user "User.Comments")
		(21 "Eco1.User" user "User.Eco1")
		(23 "Eco2.User" user "User.Eco2")
		(25 "Edge.Cuts" user "Board Geometry/Outline")
		(27 "Margin" user)
		(31 "F.CrtYd" user "Package Geometry/Place Bound Top")
		(29 "B.CrtYd" user "Package Geometry/Place Bound Bottom")
		(35 "F.Fab" user "Ref Des/Assembly Top")
		(33 "B.Fab" user "Ref Des/Assembly Bottom")
	)
	(footprint ""
		(layer "F.Cu")
		(at 180.8734 -131.7625)
		(property "Reference" "R4B7"
			(at 0 0 0)
			(layer "F.SilkS")
			(hide yes)
			(effects
				(font
					(size 1.27 1.27)
				)
			)
		)
		(property "Value" ""
			(at 0 0 0)
			(layer "F.Fab")
			(effects
				(font
					(size 1.27 1.27)
				)
			)
		)
		(duplicate_pad_numbers_are_jumpers no)
		(fp_poly
			(pts
				(xy -0.2794 -0.1016) (xy 0.2794 -0.1016) (xy 0.2794 0.9906) (xy -0.2794 0.9906)
			)
			(stroke
				(width 0)
				(type default)
			)
			(fill no)
			(layer "F.CrtYd")
		)
		(fp_line
			(start -0.2794 -0.1016)
			(end -0.2794 0.9906)
			(stroke
				(width 0.1)
				(type default)
			)
			(layer "F.Fab")
		)
		(fp_line
			(start -0.2794 0.9906)
			(end 0.2794 0.9906)
			(stroke
				(width 0.1)
				(type default)
			)
			(layer "F.Fab")
		)
		(fp_line
			(start 0.2794 -0.1016)
			(end -0.2794 -0.1016)
			(stroke
				(width 0.1)
				(type default)
			)
			(layer "F.Fab")
		)
		(fp_line
			(start 0.2794 0.9906)
			(end 0.2794 -0.1016)
			(stroke
				(width 0.1)
				(type default)
			)
			(layer "F.Fab")
		)
		(pad "1" smd rect
			(at 0 0)
			(size 0.508 0.508)
			(layers "F.Cu" "F.Mask" "F.Paste")
			(net "PWRGD_PVPP_KLM_R")
		)
		(pad "2" smd rect
			(at 0 0.889)
			(size 0.508 0.508)
			(layers "F.Cu" "F.Mask" "F.Paste")
			(net "PWRGD_PVPP_KLM")
		)
		(zone
			(layer "F.Cu")
			(hatch none 0.5)
			(connect_pads
				(clearance 0)
			)
			(min_thickness 0.25)
			(keepout
				(tracks allowed)
				(vias not_allowed)
				(pads allowed)
				(copperpour not_allowed)
				(footprints allowed)
			)
			(placement
				(enabled no)
				(sheetname "")
			)
			(fill
				(thermal_gap 0.5)
				(thermal_bridge_width 0.5)
				(island_removal_mode 0)
			)
			(polygon
				(pts
					(xy 180.6194 -131.5085) (xy 181.1274 -131.5085) (xy 181.1274 -131.1275) (xy 180.6194 -131.1275)
				)
			)
		)
		(zone
			(layer "F.Cu")
			(hatch none 0.5)
			(connect_pads
				(clearance 0)
			)
			(min_thickness 0.25)
			(keepout
				(tracks not_allowed)
				(vias allowed)
				(pads allowed)
				(copperpour not_allowed)
				(footprints allowed)
			)
			(placement
				(enabled no)
				(sheetname "")
			)
			(fill
				(thermal_gap 0.5)
				(thermal_bridge_width 0.5)
				(island_removal_mode 0)
			)
			(polygon
				(pts
					(xy 180.6194 -131.1275) (xy 181.1274 -131.1275) (xy 181.1274 -131.5085) (xy 180.6194 -131.5085)
				)
			)
		)
	)
	(footprint ""
		(layer "F.Cu")
		(at 408.051 -103.8225)
		(property "Reference" "R2N6"
			(at 0 0 0)
			(layer "F.SilkS")
			(hide yes)
			(effects
				(font
					(size 1.27 1.27)
				)
			)
		)
		(property "Value" ""
			(at 0 0 0)
			(layer "F.Fab")
			(effects
				(font
					(size 1.27 1.27)
				)
			)
		)
		(duplicate_pad_numbers_are_jumpers no)
		(fp_poly
			(pts
				(xy -0.2794 -0.1016) (xy 0.2794 -0.1016) (xy 0.2794 0.9906) (xy -0.2794 0.9906)
			)
			(stroke
				(width 0)
				(type default)
			)
			(fill no)
			(layer "F.CrtYd")
		)
		(fp_line
			(start -0.2794 -0.1016)
			(end -0.2794 0.9906)
			(stroke
				(width 0.1)
				(type default)
			)
			(layer "F.Fab")
		)
		(fp_line
			(start -0.2794 0.9906)
			(end 0.2794 0.9906)
			(stroke
				(width 0.1)
				(type default)
			)
			(layer "F.Fab")
		)
		(fp_line
			(start 0.2794 -0.1016)
			(end -0.2794 -0.1016)
			(stroke
				(width 0.1)
				(type default)
			)
			(layer "F.Fab")
		)
		(fp_line
			(start 0.2794 0.9906)
			(end 0.2794 -0.1016)
			(stroke
				(width 0.1)
				(type default)
			)
			(layer "F.Fab")
		)
		(pad "1" smd rect
			(at 0 0)
			(size 0.508 0.508)
			(layers "F.Cu" "F.Mask" "F.Paste")
			(net "P3V3_STBY")
		)
		(pad "2" smd rect
			(at 0 0.889)
			(size 0.508 0.508)
			(layers "F.Cu" "F.Mask" "F.Paste")
			(net "FM_GBE_LOM_DISABLE_N")
		)
		(zone
			(layer "F.Cu")
			(hatch none 0.5)
			(connect_pads
				(clearance 0)
			)
			(min_thickness 0.25)
			(keepout
				(tracks allowed)
				(vias not_allowed)
				(pads allowed)
				(copperpour not_allowed)
				(footprints allowed)
			)
			(placement
				(enabled no)
				(sheetname "")
			)
			(fill
				(thermal_gap 0.5)
				(thermal_bridge_width 0.5)
				(island_removal_mode 0)
			)
			(polygon
				(pts
					(xy 407.797 -103.5685) (xy 408.305 -103.5685) (xy 408.305 -103.1875) (xy 407.797 -103.1875)
				)
			)
		)
		(zone
			(layer "F.Cu")
			(hatch none 0.5)
			(connect_pads
				(clearance 0)
			)
			(min_thickness 0.25)
			(keepout
				(tracks not_allowed)
				(vias allowed)
				(pads allowed)
				(copperpour not_allowed)
				(footprints allowed)
			)
			(placement
				(enabled no)
				(sheetname "")
			)
			(fill
				(thermal_gap 0.5)
				(thermal_bridge_width 0.5)
				(island_removal_mode 0)
			)
			(polygon
				(pts
					(xy 407.797 -103.1875) (xy 408.305 -103.1875) (xy 408.305 -103.5685) (xy 407.797 -103.5685)
				)
			)
		)
	)
	(footprint ""
		(layer "F.Cu")
		(at 394.8176 -64.8462 180)
		(property "Reference" "C8E13"
			(at 0 0 180)
			(layer "F.SilkS")
			(hide yes)
			(effects
				(font
					(size 1.27 1.27)
				)
			)
		)
		(property "Value" ""
			(at 0 0 180)
			(layer "F.Fab")
			(effects
				(font
					(size 1.27 1.27)
				)
			)
		)
		(duplicate_pad_numbers_are_jumpers no)
		(fp_poly
			(pts
				(xy 0.3048 -0.1016) (xy 0.3048 0.9906) (xy -0.3048 0.9906) (xy -0.3048 -0.1016)
			)
			(stroke
				(width 0)
				(type default)
			)
			(fill no)
			(layer "F.CrtYd")
		)
		(fp_line
			(start 0.3048 0.9906)
			(end 0.3048 -0.1016)
			(stroke
				(width 0.1)
				(type default)
			)
			(layer "F.Fab")
		)
		(fp_line
			(start 0.3048 -0.1016)
			(end -0.3048 -0.1016)
			(stroke
				(width 0.1)
				(type default)
			)
			(layer "F.Fab")
		)
		(fp_line
			(start -0.3048 0.9906)
			(end 0.3048 0.9906)
			(stroke
				(width 0.1)
				(type default)
			)
			(layer "F.Fab")
		)
		(fp_line
			(start -0.3048 -0.1016)
			(end -0.3048 0.9906)
			(stroke
				(width 0.1)
				(type default)
			)
			(layer "F.Fab")
		)
		(pad "1" smd rect
			(at 0 0 180)
			(size 0.508 0.508)
			(layers "F.Cu" "F.Mask" "F.Paste")
			(net "PWRGD_P12V_HSC_DLY")
		)
		(pad "2" smd rect
			(at 0 0.889 180)
			(size 0.508 0.508)
			(layers "F.Cu" "F.Mask" "F.Paste")
			(net "AGND_P5V_STBY")
		)
		(zone
			(layer "F.Cu")
			(hatch none 0.5)
			(connect_pads
				(clearance 0)
			)
			(min_thickness 0.25)
			(keepout
				(tracks not_allowed)
				(vias allowed)
				(pads allowed)
				(copperpour not_allowed)
				(footprints allowed)
			)
			(placement
				(enabled no)
				(sheetname "")
			)
			(fill
				(thermal_gap 0.5)
				(thermal_bridge_width 0.5)
				(island_removal_mode 0)
			)
			(polygon
				(pts
					(xy 395.0716 -65.4812) (xy 394.5636 -65.4812) (xy 394.5636 -65.1002) (xy 395.0716 -65.1002)
				)
			)
		)
		(zone
			(layer "F.Cu")
			(hatch none 0.5)
			(connect_pads
				(clearance 0)
			)
			(min_thickness 0.25)
			(keepout
				(tracks allowed)
				(vias not_allowed)
				(pads allowed)
				(copperpour not_allowed)
				(footprints allowed)
			)
			(placement
				(enabled no)
				(sheetname "")
			)
			(fill
				(thermal_gap 0.5)
				(thermal_bridge_width 0.5)
				(island_removal_mode 0)
			)
			(polygon
				(pts
					(xy 395.0716 -65.1002) (xy 394.5636 -65.1002) (xy 394.5636 -65.4812) (xy 395.0716 -65.4812)
				)
			)
		)
	)
)
